(kicad_pcb
	(version 20260206)
	(generator "pcbnew")
	(generator_version "10.0")
	(general
		(thickness 1.6)
		(legacy_teardrops no)
	)
	(paper "A4")
	(title_block
		(title "03242023_DA0F0TMBIJ0_F0T_Motherboard_J_brd_V01_OCP.brd")
		(comment 1 "Grand Teton / footprints 515-521 of 6105")
	)
	(layers
		(0 "F.Cu" signal "TOP")
		(4 "In1.Cu" signal "GND")
		(6 "In2.Cu" signal "IN1")
		(8 "In3.Cu" signal "GND1")
		(10 "In4.Cu" signal "IN2")
		(12 "In5.Cu" signal "GND2")
		(14 "In6.Cu" signal "IN3")
		(16 "In7.Cu" signal "GND3")
		(18 "In8.Cu" signal "VCC")
		(20 "In9.Cu" signal "VCC1")
		(22 "In10.Cu" signal "GND4")
		(24 "In11.Cu" signal "IN4")
		(26 "In12.Cu" signal "GND5")
		(28 "In13.Cu" signal "IN5")
		(30 "In14.Cu" signal "GND6")
		(32 "In15.Cu" signal "IN6")
		(34 "In16.Cu" signal "GND7")
		(2 "B.Cu" signal "BOTTOM")
		(9 "F.Adhes" user "F.Adhesive")
		(11 "B.Adhes" user "B.Adhesive")
		(13 "F.Paste" user "Package Geometry/Pastemask Top")
		(15 "B.Paste" user "Package Geometry/Pastemask Bottom")
		(5 "F.SilkS" user "Ref Des/Silkscreen Top")
		(7 "B.SilkS" user "Ref Des/Silkscreen Bottom")
		(1 "F.Mask" user "Board Geometry/Soldermask Top")
		(3 "B.Mask" user "Board Geometry/Soldermask Bottom")
		(17 "Dwgs.User" user "User.Drawings")
		(19 "Cmts.User" user "User.Comments")
		(21 "Eco1.User" user "User.Eco1")
		(23 "Eco2.User" user "User.Eco2")
		(25 "Edge.Cuts" user "Board Geometry/Outline")
		(27 "Margin" user)
		(31 "F.CrtYd" user "Package Geometry/Place Bound Top")
		(29 "B.CrtYd" user "Package Geometry/Place Bound Bottom")
		(35 "F.Fab" user "Ref Des/Assembly Top")
		(33 "B.Fab" user "Ref Des/Assembly Bottom")
	)
	(footprint ""
		(layer "F.Cu")
		(at 126.065026 -339.602572 90)
		(property "Reference" "PC502"
			(at 0 0 90)
			(layer "F.SilkS")
			(hide yes)
			(effects
				(font
					(size 1.27 1.27)
				)
			)
		)
		(property "Value" ""
			(at 0 0 90)
			(layer "F.Fab")
			(effects
				(font
					(size 1.27 1.27)
				)
			)
		)
		(duplicate_pad_numbers_are_jumpers no)
		(fp_line
			(start 0.7874 -0.4064)
			(end 0.7874 0.4064)
			(stroke
				(width 0.1524)
				(type default)
			)
			(layer "F.SilkS")
		)
		(fp_line
			(start -0.7874 -0.4064)
			(end 0.7874 -0.4064)
			(stroke
				(width 0.1524)
				(type default)
			)
			(layer "F.SilkS")
		)
		(fp_line
			(start 0.7874 0.4064)
			(end -0.7874 0.4064)
			(stroke
				(width 0.1524)
				(type default)
			)
			(layer "F.SilkS")
		)
		(fp_line
			(start -0.7874 0.4064)
			(end -0.7874 -0.4064)
			(stroke
				(width 0.1524)
				(type default)
			)
			(layer "F.SilkS")
		)
		(fp_line
			(start -0.12065 -0.305054)
			(end -0.12065 -0.2794)
			(stroke
				(width 0.1)
				(type default)
			)
			(layer "F.Fab")
		)
		(fp_line
			(start -0.67945 -0.305054)
			(end -0.12065 -0.305054)
			(stroke
				(width 0.1)
				(type default)
			)
			(layer "F.Fab")
		)
		(fp_line
			(start 0.67945 -0.3048)
			(end 0.67945 0.3048)
			(stroke
				(width 0.1)
				(type default)
			)
			(layer "F.Fab")
		)
		(fp_line
			(start 0.12065 -0.3048)
			(end 0.67945 -0.3048)
			(stroke
				(width 0.1)
				(type default)
			)
			(layer "F.Fab")
		)
		(fp_line
			(start 0.12065 -0.2794)
			(end 0.12065 -0.3048)
			(stroke
				(width 0.1)
				(type default)
			)
			(layer "F.Fab")
		)
		(fp_line
			(start -0.12065 -0.2794)
			(end 0.12065 -0.2794)
			(stroke
				(width 0.1)
				(type default)
			)
			(layer "F.Fab")
		)
		(fp_line
			(start 0.120396 0.2794)
			(end -0.12065 0.2794)
			(stroke
				(width 0.1)
				(type default)
			)
			(layer "F.Fab")
		)
		(fp_line
			(start -0.12065 0.2794)
			(end -0.12065 0.3048)
			(stroke
				(width 0.1)
				(type default)
			)
			(layer "F.Fab")
		)
		(fp_line
			(start 0.67945 0.3048)
			(end 0.120396 0.3048)
			(stroke
				(width 0.1)
				(type default)
			)
			(layer "F.Fab")
		)
		(fp_line
			(start 0.120396 0.3048)
			(end 0.120396 0.2794)
			(stroke
				(width 0.1)
				(type default)
			)
			(layer "F.Fab")
		)
		(fp_line
			(start -0.12065 0.3048)
			(end -0.67945 0.3048)
			(stroke
				(width 0.1)
				(type default)
			)
			(layer "F.Fab")
		)
		(fp_line
			(start -0.67945 0.3048)
			(end -0.67945 -0.305054)
			(stroke
				(width 0.1)
				(type default)
			)
			(layer "F.Fab")
		)
		(pad "1" smd circle
			(at -0.40005 0 90)
			(size 0 0)
			(layers "F.Cu" "F.Mask" "F.Paste")
			(net "PVCCIN_CPU1_VDD5")
		)
		(pad "2" smd circle
			(at 0.40005 0 90)
			(size 0 0)
			(layers "F.Cu" "F.Mask" "F.Paste")
			(net "GND")
		)
	)
	(footprint ""
		(layer "F.Cu")
		(at 95.249238 -408.517344 -90)
		(property "Reference" "C678"
			(at 0 0 270)
			(layer "F.SilkS")
			(hide yes)
			(effects
				(font
					(size 1.27 1.27)
				)
			)
		)
		(property "Value" ""
			(at 0 0 270)
			(layer "F.Fab")
			(effects
				(font
					(size 1.27 1.27)
				)
			)
		)
		(duplicate_pad_numbers_are_jumpers no)
		(fp_line
			(start -0.299974 0.150114)
			(end -0.299974 -0.150114)
			(stroke
				(width 0.1)
				(type default)
			)
			(layer "F.Fab")
		)
		(fp_line
			(start 0.299974 0.150114)
			(end -0.299974 0.150114)
			(stroke
				(width 0.1)
				(type default)
			)
			(layer "F.Fab")
		)
		(fp_line
			(start -0.299974 -0.150114)
			(end 0.299974 -0.150114)
			(stroke
				(width 0.1)
				(type default)
			)
			(layer "F.Fab")
		)
		(fp_line
			(start 0.299974 -0.150114)
			(end 0.299974 0.150114)
			(stroke
				(width 0.1)
				(type default)
			)
			(layer "F.Fab")
		)
		(pad "1" smd rect
			(at -0.2667 0 270)
			(size 0.3048 0.381)
			(layers "F.Cu" "F.Mask" "F.Paste")
			(net "P5E_CPU1_PE4_TX_C_DN<15>")
		)
		(pad "2" smd rect
			(at 0.2667 0 270)
			(size 0.3048 0.381)
			(layers "F.Cu" "F.Mask" "F.Paste")
			(net "P5E_CPU1_PE4_TX_DN<15>")
		)
	)
	(footprint ""
		(layer "F.Cu")
		(at 111.13008 -122.132598 90)
		(property "Reference" "R932"
			(at 0 0 90)
			(layer "F.SilkS")
			(hide yes)
			(effects
				(font
					(size 1.27 1.27)
				)
			)
		)
		(property "Value" ""
			(at 0 0 90)
			(layer "F.Fab")
			(effects
				(font
					(size 1.27 1.27)
				)
			)
		)
		(duplicate_pad_numbers_are_jumpers no)
		(fp_line
			(start 0.7874 -0.4064)
			(end 0.7874 0.4064)
			(stroke
				(width 0.1524)
				(type default)
			)
			(layer "F.SilkS")
		)
		(fp_line
			(start -0.7874 -0.4064)
			(end 0.7874 -0.4064)
			(stroke
				(width 0.1524)
				(type default)
			)
			(layer "F.SilkS")
		)
		(fp_line
			(start 0.7874 0.4064)
			(end -0.7874 0.4064)
			(stroke
				(width 0.1524)
				(type default)
			)
			(layer "F.SilkS")
		)
		(fp_line
			(start -0.7874 0.4064)
			(end -0.7874 -0.4064)
			(stroke
				(width 0.1524)
				(type default)
			)
			(layer "F.SilkS")
		)
		(fp_line
			(start -0.12065 -0.305054)
			(end -0.12065 -0.2794)
			(stroke
				(width 0.1)
				(type default)
			)
			(layer "F.Fab")
		)
		(fp_line
			(start -0.67945 -0.305054)
			(end -0.12065 -0.305054)
			(stroke
				(width 0.1)
				(type default)
			)
			(layer "F.Fab")
		)
		(fp_line
			(start 0.67945 -0.3048)
			(end 0.67945 0.3048)
			(stroke
				(width 0.1)
				(type default)
			)
			(layer "F.Fab")
		)
		(fp_line
			(start 0.12065 -0.3048)
			(end 0.67945 -0.3048)
			(stroke
				(width 0.1)
				(type default)
			)
			(layer "F.Fab")
		)
		(fp_line
			(start 0.12065 -0.2794)
			(end 0.12065 -0.3048)
			(stroke
				(width 0.1)
				(type default)
			)
			(layer "F.Fab")
		)
		(fp_line
			(start -0.12065 -0.2794)
			(end 0.12065 -0.2794)
			(stroke
				(width 0.1)
				(type default)
			)
			(layer "F.Fab")
		)
		(fp_line
			(start 0.120396 0.2794)
			(end -0.12065 0.2794)
			(stroke
				(width 0.1)
				(type default)
			)
			(layer "F.Fab")
		)
		(fp_line
			(start -0.12065 0.2794)
			(end -0.12065 0.3048)
			(stroke
				(width 0.1)
				(type default)
			)
			(layer "F.Fab")
		)
		(fp_line
			(start 0.67945 0.3048)
			(end 0.120396 0.3048)
			(stroke
				(width 0.1)
				(type default)
			)
			(layer "F.Fab")
		)
		(fp_line
			(start 0.120396 0.3048)
			(end 0.120396 0.2794)
			(stroke
				(width 0.1)
				(type default)
			)
			(layer "F.Fab")
		)
		(fp_line
			(start -0.12065 0.3048)
			(end -0.67945 0.3048)
			(stroke
				(width 0.1)
				(type default)
			)
			(layer "F.Fab")
		)
		(fp_line
			(start -0.67945 0.3048)
			(end -0.67945 -0.305054)
			(stroke
				(width 0.1)
				(type default)
			)
			(layer "F.Fab")
		)
		(pad "1" smd circle
			(at -0.40005 0 90)
			(size 0 0)
			(layers "F.Cu" "F.Mask" "F.Paste")
			(net "RST_CPU0_DRAM_AB_N")
		)
		(pad "2" smd circle
			(at 0.40005 0 90)
			(size 0 0)
			(layers "F.Cu" "F.Mask" "F.Paste")
			(net "GND")
		)
	)
	(footprint ""
		(layer "F.Cu")
		(at 445.19088 -94.602808)
		(property "Reference" "R3563"
			(at 0 0 0)
			(layer "F.SilkS")
			(hide yes)
			(effects
				(font
					(size 1.27 1.27)
				)
			)
		)
		(property "Value" ""
			(at 0 0 0)
			(layer "F.Fab")
			(effects
				(font
					(size 1.27 1.27)
				)
			)
		)
		(duplicate_pad_numbers_are_jumpers no)
		(fp_line
			(start -0.7874 -0.4064)
			(end 0.7874 -0.4064)
			(stroke
				(width 0.1524)
				(type default)
			)
			(layer "F.SilkS")
		)
		(fp_line
			(start -0.7874 0.4064)
			(end -0.7874 -0.4064)
			(stroke
				(width 0.1524)
				(type default)
			)
			(layer "F.SilkS")
		)
		(fp_line
			(start 0.7874 -0.4064)
			(end 0.7874 0.4064)
			(stroke
				(width 0.1524)
				(type default)
			)
			(layer "F.SilkS")
		)
		(fp_line
			(start 0.7874 0.4064)
			(end -0.7874 0.4064)
			(stroke
				(width 0.1524)
				(type default)
			)
			(layer "F.SilkS")
		)
		(fp_line
			(start -0.67945 -0.305054)
			(end -0.12065 -0.305054)
			(stroke
				(width 0.1)
				(type default)
			)
			(layer "F.Fab")
		)
		(fp_line
			(start -0.67945 0.3048)
			(end -0.67945 -0.305054)
			(stroke
				(width 0.1)
				(type default)
			)
			(layer "F.Fab")
		)
		(fp_line
			(start -0.12065 -0.305054)
			(end -0.12065 -0.2794)
			(stroke
				(width 0.1)
				(type default)
			)
			(layer "F.Fab")
		)
		(fp_line
			(start -0.12065 -0.2794)
			(end 0.12065 -0.2794)
			(stroke
				(width 0.1)
				(type default)
			)
			(layer "F.Fab")
		)
		(fp_line
			(start -0.12065 0.2794)
			(end -0.12065 0.3048)
			(stroke
				(width 0.1)
				(type default)
			)
			(layer "F.Fab")
		)
		(fp_line
			(start -0.12065 0.3048)
			(end -0.67945 0.3048)
			(stroke
				(width 0.1)
				(type default)
			)
			(layer "F.Fab")
		)
		(fp_line
			(start 0.120396 0.2794)
			(end -0.12065 0.2794)
			(stroke
				(width 0.1)
				(type default)
			)
			(layer "F.Fab")
		)
		(fp_line
			(start 0.120396 0.3048)
			(end 0.120396 0.2794)
			(stroke
				(width 0.1)
				(type default)
			)
			(layer "F.Fab")
		)
		(fp_line
			(start 0.12065 -0.3048)
			(end 0.67945 -0.3048)
			(stroke
				(width 0.1)
				(type default)
			)
			(layer "F.Fab")
		)
		(fp_line
			(start 0.12065 -0.2794)
			(end 0.12065 -0.3048)
			(stroke
				(width 0.1)
				(type default)
			)
			(layer "F.Fab")
		)
		(fp_line
			(start 0.67945 -0.3048)
			(end 0.67945 0.3048)
			(stroke
				(width 0.1)
				(type default)
			)
			(layer "F.Fab")
		)
		(fp_line
			(start 0.67945 0.3048)
			(end 0.120396 0.3048)
			(stroke
				(width 0.1)
				(type default)
			)
			(layer "F.Fab")
		)
		(pad "1" smd circle
			(at -0.40005 0)
			(size 0 0)
			(layers "F.Cu" "F.Mask" "F.Paste")
			(net "OCP_SFF_P3V3_ADC_ALERT_R")
		)
		(pad "2" smd circle
			(at 0.40005 0)
			(size 0 0)
			(layers "F.Cu" "F.Mask" "F.Paste")
			(net "OCP_SFF_P3V3_ADC_ALERT")
		)
	)
	(footprint ""
		(layer "F.Cu")
		(at 482.66985 -242.495832 90)
		(property "Reference" "X34"
			(at -0.1778 -1.92913 90)
			(unlocked yes)
			(layer "F.SilkS")
			(effects
				(font
					(size 0.7874 0.5842)
					(thickness 0.1524)
				)
				(justify left)
			)
		)
		(property "Value" ""
			(at 0 0 90)
			(layer "F.Fab")
			(effects
				(font
					(size 1.27 1.27)
				)
			)
		)
		(property "Device Type" "TP_TDR_4P_FTS_TH-TP_TDR_4P_DIPA"
			(at 1.30175 1.27 180)
			(unlocked yes)
			(layer "F.Fab")
			(hide yes)
			(effects
				(font
					(size 0.635 0.4064)
					(thickness 0.1524)
				)
			)
		)
		(property "User Part Number" "N_A"
			(at 1.30175 1.27 180)
			(unlocked yes)
			(layer "Cmts.User")
			(hide yes)
			(effects
				(font
					(size 0.635 0.4064)
					(thickness 0.1524)
				)
			)
		)
		(duplicate_pad_numbers_are_jumpers no)
		(fp_line
			(start 2.54 -1.27)
			(end 0 -1.27)
			(stroke
				(width 0.1524)
				(type default)
			)
			(layer "F.SilkS")
		)
		(fp_line
			(start 0 -1.27)
			(end 0 -0.635)
			(stroke
				(width 0.1524)
				(type default)
			)
			(layer "F.SilkS")
		)
		(fp_line
			(start 2.54 -1.1303)
			(end 2.54 -1.27)
			(stroke
				(width 0.1524)
				(type default)
			)
			(layer "F.SilkS")
		)
		(fp_line
			(start 0 0.635)
			(end 0 1.905)
			(stroke
				(width 0.1524)
				(type default)
			)
			(layer "F.SilkS")
		)
		(fp_line
			(start 2.54 1.4097)
			(end 2.54 1.1303)
			(stroke
				(width 0.1524)
				(type default)
			)
			(layer "F.SilkS")
		)
		(fp_line
			(start 0 3.175)
			(end 0 3.81)
			(stroke
				(width 0.1524)
				(type default)
			)
			(layer "F.SilkS")
		)
		(fp_line
			(start 2.54 3.81)
			(end 2.54 3.6703)
			(stroke
				(width 0.1524)
				(type default)
			)
			(layer "F.SilkS")
		)
		(fp_line
			(start 0 3.81)
			(end 2.54 3.81)
			(stroke
				(width 0.1524)
				(type default)
			)
			(layer "F.SilkS")
		)
		(fp_poly
			(pts
				(xy -0.761746 0) (xy -2.285746 -0.762) (xy -2.285746 0.762)
			)
			(stroke
				(width 0)
				(type default)
			)
			(fill yes)
			(layer "F.SilkS")
		)
		(fp_line
			(start 2.54 -1.27)
			(end 0 -1.27)
			(stroke
				(width 0.1)
				(type default)
			)
			(layer "F.Fab")
		)
		(fp_line
			(start 0 -1.27)
			(end 0 3.81)
			(stroke
				(width 0.1)
				(type default)
			)
			(layer "F.Fab")
		)
		(fp_line
			(start 2.54 3.81)
			(end 2.54 -1.27)
			(stroke
				(width 0.1)
				(type default)
			)
			(layer "F.Fab")
		)
		(fp_line
			(start 0 3.81)
			(end 2.54 3.81)
			(stroke
				(width 0.1)
				(type default)
			)
			(layer "F.Fab")
		)
		(fp_poly
			(pts
				(xy -0.761746 0) (xy -2.285746 -0.762) (xy -2.285746 0.762)
			)
			(stroke
				(width 0)
				(type default)
			)
			(fill yes)
			(layer "F.Fab")
		)
		(pad "1" thru_hole circle
			(at 0 0 90)
			(size 1.0033 1.0033)
			(drill 0.249936)
			(layers "*.Cu" "*.Mask")
			(remove_unused_layers no)
			(net "TDR_DIFF_85_NECK_IN1_DP")
			(clearance 0.10795)
			(thermal_gap 0.10795)
			(padstack
				(mode front_inner_back)
				(layer "Inner"
					(shape circle)
					(size 0.8001 0.8001)
					(clearance 0.1524)
				)
				(layer "B.Cu"
					(shape circle)
					(size 1.0033 1.0033)
					(clearance 0.10795)
				)
			)
		)
		(pad "2" thru_hole circle
			(at 2.54 0 90)
			(size 1.9939 1.9939)
			(drill 0.249936)
			(layers "*.Cu" "*.Mask")
			(remove_unused_layers no)
			(net "T1_GND")
			(clearance 0.10795)
			(thermal_gap 0.10795)
			(padstack
				(mode front_inner_back)
				(layer "Inner"
					(shape circle)
					(size 0.8001 0.8001)
					(clearance 0.1524)
				)
				(layer "B.Cu"
					(shape circle)
					(size 1.9939 1.9939)
					(clearance 0.10795)
				)
			)
		)
		(pad "3" thru_hole circle
			(at 2.54 2.54 90)
			(size 1.9939 1.9939)
			(drill 0.249936)
			(layers "*.Cu" "*.Mask")
			(remove_unused_layers no)
			(net "T1_GND")
			(clearance 0.10795)
			(thermal_gap 0.10795)
			(padstack
				(mode front_inner_back)
				(layer "Inner"
					(shape circle)
					(size 0.8001 0.8001)
					(clearance 0.1524)
				)
				(layer "B.Cu"
					(shape circle)
					(size 1.9939 1.9939)
					(clearance 0.10795)
				)
			)
		)
		(pad "4" thru_hole circle
			(at 0 2.54 90)
			(size 1.0033 1.0033)
			(drill 0.249936)
			(layers "*.Cu" "*.Mask")
			(remove_unused_layers no)
			(net "TDR_DIFF_85_NECK_IN1_DN")
			(clearance 0.10795)
			(thermal_gap 0.10795)
			(padstack
				(mode front_inner_back)
				(layer "Inner"
					(shape circle)
					(size 0.8001 0.8001)
					(clearance 0.1524)
				)
				(layer "B.Cu"
					(shape circle)
					(size 1.0033 1.0033)
					(clearance 0.10795)
				)
			)
		)
	)
	(footprint ""
		(layer "F.Cu")
		(at 31.937452 -164.364162)
		(property "Reference" "PC393"
			(at 0 0 0)
			(layer "F.SilkS")
			(hide yes)
			(effects
				(font
					(size 1.27 1.27)
				)
			)
		)
		(property "Value" ""
			(at 0 0 0)
			(layer "F.Fab")
			(effects
				(font
					(size 1.27 1.27)
				)
			)
		)
		(duplicate_pad_numbers_are_jumpers no)
		(fp_line
			(start -0.7874 -0.4064)
			(end 0.7874 -0.4064)
			(stroke
				(width 0.1524)
				(type default)
			)
			(layer "F.SilkS")
		)
		(fp_line
			(start -0.7874 0.4064)
			(end -0.7874 -0.4064)
			(stroke
				(width 0.1524)
				(type default)
			)
			(layer "F.SilkS")
		)
		(fp_line
			(start 0.7874 -0.4064)
			(end 0.7874 0.4064)
			(stroke
				(width 0.1524)
				(type default)
			)
			(layer "F.SilkS")
		)
		(fp_line
			(start 0.7874 0.4064)
			(end -0.7874 0.4064)
			(stroke
				(width 0.1524)
				(type default)
			)
			(layer "F.SilkS")
		)
		(fp_line
			(start -0.67945 -0.305054)
			(end -0.12065 -0.305054)
			(stroke
				(width 0.1)
				(type default)
			)
			(layer "F.Fab")
		)
		(fp_line
			(start -0.67945 0.3048)
			(end -0.67945 -0.305054)
			(stroke
				(width 0.1)
				(type default)
			)
			(layer "F.Fab")
		)
		(fp_line
			(start -0.12065 -0.305054)
			(end -0.12065 -0.2794)
			(stroke
				(width 0.1)
				(type default)
			)
			(layer "F.Fab")
		)
		(fp_line
			(start -0.12065 -0.2794)
			(end 0.12065 -0.2794)
			(stroke
				(width 0.1)
				(type default)
			)
			(layer "F.Fab")
		)
		(fp_line
			(start -0.12065 0.2794)
			(end -0.12065 0.3048)
			(stroke
				(width 0.1)
				(type default)
			)
			(layer "F.Fab")
		)
		(fp_line
			(start -0.12065 0.3048)
			(end -0.67945 0.3048)
			(stroke
				(width 0.1)
				(type default)
			)
			(layer "F.Fab")
		)
		(fp_line
			(start 0.120396 0.2794)
			(end -0.12065 0.2794)
			(stroke
				(width 0.1)
				(type default)
			)
			(layer "F.Fab")
		)
		(fp_line
			(start 0.120396 0.3048)
			(end 0.120396 0.2794)
			(stroke
				(width 0.1)
				(type default)
			)
			(layer "F.Fab")
		)
		(fp_line
			(start 0.12065 -0.3048)
			(end 0.67945 -0.3048)
			(stroke
				(width 0.1)
				(type default)
			)
			(layer "F.Fab")
		)
		(fp_line
			(start 0.12065 -0.2794)
			(end 0.12065 -0.3048)
			(stroke
				(width 0.1)
				(type default)
			)
			(layer "F.Fab")
		)
		(fp_line
			(start 0.67945 -0.3048)
			(end 0.67945 0.3048)
			(stroke
				(width 0.1)
				(type default)
			)
			(layer "F.Fab")
		)
		(fp_line
			(start 0.67945 0.3048)
			(end 0.120396 0.3048)
			(stroke
				(width 0.1)
				(type default)
			)
			(layer "F.Fab")
		)
		(pad "1" smd circle
			(at -0.40005 0)
			(size 0 0)
			(layers "F.Cu" "F.Mask" "F.Paste")
			(net "PVCCD_HV_CPU1_ATSEN")
		)
		(pad "2" smd circle
			(at 0.40005 0)
			(size 0 0)
			(layers "F.Cu" "F.Mask" "F.Paste")
			(net "GND")
		)
	)
	(footprint ""
		(layer "F.Cu")
		(at 96.163638 -408.517344 -90)
		(property "Reference" "C679"
			(at 0 0 270)
			(layer "F.SilkS")
			(hide yes)
			(effects
				(font
					(size 1.27 1.27)
				)
			)
		)
		(property "Value" ""
			(at 0 0 270)
			(layer "F.Fab")
			(effects
				(font
					(size 1.27 1.27)
				)
			)
		)
		(duplicate_pad_numbers_are_jumpers no)
		(fp_line
			(start -0.299974 0.150114)
			(end -0.299974 -0.150114)
			(stroke
				(width 0.1)
				(type default)
			)
			(layer "F.Fab")
		)
		(fp_line
			(start 0.299974 0.150114)
			(end -0.299974 0.150114)
			(stroke
				(width 0.1)
				(type default)
			)
			(layer "F.Fab")
		)
		(fp_line
			(start -0.299974 -0.150114)
			(end 0.299974 -0.150114)
			(stroke
				(width 0.1)
				(type default)
			)
			(layer "F.Fab")
		)
		(fp_line
			(start 0.299974 -0.150114)
			(end 0.299974 0.150114)
			(stroke
				(width 0.1)
				(type default)
			)
			(layer "F.Fab")
		)
		(pad "1" smd rect
			(at -0.2667 0 270)
			(size 0.3048 0.381)
			(layers "F.Cu" "F.Mask" "F.Paste")
			(net "P5E_CPU1_PE4_TX_C_DP<15>")
		)
		(pad "2" smd rect
			(at 0.2667 0 270)
			(size 0.3048 0.381)
			(layers "F.Cu" "F.Mask" "F.Paste")
			(net "P5E_CPU1_PE4_TX_DP<15>")
		)
	)
)
